# S9S_MB_2U (Grand Teton) — schematic netlist excerpt (pin names and nets, part order shuffled) for the footprints in the layout excerpt that follows; sources: Cadence DE-HDL packaged netlist, KiCad conversion of 03242023_DA0F0TMBIJ0_F0T_Motherboard_J_brd_V01_OCP.brd

C418  Q_CAP  22UF 4V 20% X6S  pkg C0402  page 74 : A = PVCCFA_EHV_FIVRA_CPU0 ; B = GND
R1318  Q_RES  0 5% CHIP  pkg 0402LF  page 223 : A = FM_THERMTRIP_DLY_LVC1_R_N ; B = FM_THERMTRIP_DLY_LVC1_N

(kicad_pcb
	(version 20260206)
	(generator "pcbnew")
	(generator_version "10.0")
	(general
		(thickness 1.6)
		(legacy_teardrops no)
	)
	(paper "A4")
	(title_block
		(title "03242023_DA0F0TMBIJ0_F0T_Motherboard_J_brd_V01_OCP.brd")
		(comment 1 "Grand Teton / footprints 3872-3873 of 6105")
	)
	(layers
		(0 "F.Cu" signal "TOP")
		(4 "In1.Cu" signal "GND")
		(6 "In2.Cu" signal "IN1")
		(8 "In3.Cu" signal "GND1")
		(10 "In4.Cu" signal "IN2")
		(12 "In5.Cu" signal "GND2")
		(14 "In6.Cu" signal "IN3")
		(16 "In7.Cu" signal "GND3")
		(18 "In8.Cu" signal "VCC")
		(20 "In9.Cu" signal "VCC1")
		(22 "In10.Cu" signal "GND4")
		(24 "In11.Cu" signal "IN4")
		(26 "In12.Cu" signal "GND5")
		(28 "In13.Cu" signal "IN5")
		(30 "In14.Cu" signal "GND6")
		(32 "In15.Cu" signal "IN6")
		(34 "In16.Cu" signal "GND7")
		(2 "B.Cu" signal "BOTTOM")
		(9 "F.Adhes" user "F.Adhesive")
		(11 "B.Adhes" user "B.Adhesive")
		(13 "F.Paste" user "Package Geometry/Pastemask Top")
		(15 "B.Paste" user "Package Geometry/Pastemask Bottom")
		(5 "F.SilkS" user "Ref Des/Silkscreen Top")
		(7 "B.SilkS" user "Ref Des/Silkscreen Bottom")
		(1 "F.Mask" user "Board Geometry/Soldermask Top")
		(3 "B.Mask" user "Board Geometry/Soldermask Bottom")
		(17 "Dwgs.User" user "User.Drawings")
		(19 "Cmts.User" user "User.Comments")
		(21 "Eco1.User" user "User.Eco1")
		(23 "Eco2.User" user "User.Eco2")
		(25 "Edge.Cuts" user "Board Geometry/Outline")
		(27 "Margin" user)
		(31 "F.CrtYd" user "Package Geometry/Place Bound Top")
		(29 "B.CrtYd" user "Package Geometry/Place Bound Bottom")
		(35 "F.Fab" user "Ref Des/Assembly Top")
		(33 "B.Fab" user "Ref Des/Assembly Bottom")
	)
	(footprint ""
		(layer "F.Cu")
		(at 352.281744 -240.276888 90)
		(property "Reference" "C418"
			(at 0 0 90)
			(layer "F.SilkS")
			(hide yes)
			(effects
				(font
					(size 1.27 1.27)
				)
			)
		)
		(property "Value" ""
			(at 0 0 90)
			(layer "F.Fab")
			(effects
				(font
					(size 1.27 1.27)
				)
			)
		)
		(duplicate_pad_numbers_are_jumpers no)
		(fp_line
			(start 0.7874 -0.4064)
			(end 0.7874 0.4064)
			(stroke
				(width 0.1524)
				(type default)
			)
			(layer "F.SilkS")
		)
		(fp_line
			(start -0.7874 -0.4064)
			(end 0.7874 -0.4064)
			(stroke
				(width 0.1524)
				(type default)
			)
			(layer "F.SilkS")
		)
		(fp_line
			(start 0.7874 0.4064)
			(end -0.7874 0.4064)
			(stroke
				(width 0.1524)
				(type default)
			)
			(layer "F.SilkS")
		)
		(fp_line
			(start -0.7874 0.4064)
			(end -0.7874 -0.4064)
			(stroke
				(width 0.1524)
				(type default)
			)
			(layer "F.SilkS")
		)
		(fp_line
			(start -0.12065 -0.305054)
			(end -0.12065 -0.2794)
			(stroke
				(width 0.1)
				(type default)
			)
			(layer "F.Fab")
		)
		(fp_line
			(start -0.67945 -0.305054)
			(end -0.12065 -0.305054)
			(stroke
				(width 0.1)
				(type default)
			)
			(layer "F.Fab")
		)
		(fp_line
			(start 0.67945 -0.3048)
			(end 0.67945 0.3048)
			(stroke
				(width 0.1)
				(type default)
			)
			(layer "F.Fab")
		)
		(fp_line
			(start 0.12065 -0.3048)
			(end 0.67945 -0.3048)
			(stroke
				(width 0.1)
				(type default)
			)
			(layer "F.Fab")
		)
		(fp_line
			(start 0.12065 -0.2794)
			(end 0.12065 -0.3048)
			(stroke
				(width 0.1)
				(type default)
			)
			(layer "F.Fab")
		)
		(fp_line
			(start -0.12065 -0.2794)
			(end 0.12065 -0.2794)
			(stroke
				(width 0.1)
				(type default)
			)
			(layer "F.Fab")
		)
		(fp_line
			(start 0.120396 0.2794)
			(end -0.12065 0.2794)
			(stroke
				(width 0.1)
				(type default)
			)
			(layer "F.Fab")
		)
		(fp_line
			(start -0.12065 0.2794)
			(end -0.12065 0.3048)
			(stroke
				(width 0.1)
				(type default)
			)
			(layer "F.Fab")
		)
		(fp_line
			(start 0.67945 0.3048)
			(end 0.120396 0.3048)
			(stroke
				(width 0.1)
				(type default)
			)
			(layer "F.Fab")
		)
		(fp_line
			(start 0.120396 0.3048)
			(end 0.120396 0.2794)
			(stroke
				(width 0.1)
				(type default)
			)
			(layer "F.Fab")
		)
		(fp_line
			(start -0.12065 0.3048)
			(end -0.67945 0.3048)
			(stroke
				(width 0.1)
				(type default)
			)
			(layer "F.Fab")
		)
		(fp_line
			(start -0.67945 0.3048)
			(end -0.67945 -0.305054)
			(stroke
				(width 0.1)
				(type default)
			)
			(layer "F.Fab")
		)
		(pad "1" smd circle
			(at -0.40005 0 90)
			(size 0 0)
			(layers "F.Cu" "F.Mask" "F.Paste")
			(net "PVCCFA_EHV_FIVRA_CPU0")
		)
		(pad "2" smd circle
			(at 0.40005 0 90)
			(size 0 0)
			(layers "F.Cu" "F.Mask" "F.Paste")
			(net "GND")
		)
	)
	(footprint ""
		(layer "F.Cu")
		(at 188.0108 -93.91015 -90)
		(property "Reference" "R1318"
			(at 0 0 270)
			(layer "F.SilkS")
			(hide yes)
			(effects
				(font
					(size 1.27 1.27)
				)
			)
		)
		(property "Value" ""
			(at 0 0 270)
			(layer "F.Fab")
			(effects
				(font
					(size 1.27 1.27)
				)
			)
		)
		(duplicate_pad_numbers_are_jumpers no)
		(fp_line
			(start -0.7874 0.4064)
			(end -0.7874 -0.4064)
			(stroke
				(width 0.1524)
				(type default)
			)
			(layer "F.SilkS")
		)
		(fp_line
			(start 0.7874 0.4064)
			(end -0.7874 0.4064)
			(stroke
				(width 0.1524)
				(type default)
			)
			(layer "F.SilkS")
		)
		(fp_line
			(start -0.7874 -0.4064)
			(end 0.7874 -0.4064)
			(stroke
				(width 0.1524)
				(type default)
			)
			(layer "F.SilkS")
		)
		(fp_line
			(start 0.7874 -0.4064)
			(end 0.7874 0.4064)
			(stroke
				(width 0.1524)
				(type default)
			)
			(layer "F.SilkS")
		)
		(fp_line
			(start -0.67945 0.3048)
			(end -0.67945 -0.305054)
			(stroke
				(width 0.1)
				(type default)
			)
			(layer "F.Fab")
		)
		(fp_line
			(start -0.12065 0.3048)
			(end -0.67945 0.3048)
			(stroke
				(width 0.1)
				(type default)
			)
			(layer "F.Fab")
		)
		(fp_line
			(start 0.120396 0.3048)
			(end 0.120396 0.2794)
			(stroke
				(width 0.1)
				(type default)
			)
			(layer "F.Fab")
		)
		(fp_line
			(start 0.67945 0.3048)
			(end 0.120396 0.3048)
			(stroke
				(width 0.1)
				(type default)
			)
			(layer "F.Fab")
		)
		(fp_line
			(start -0.12065 0.2794)
			(end -0.12065 0.3048)
			(stroke
				(width 0.1)
				(type default)
			)
			(layer "F.Fab")
		)
		(fp_line
			(start 0.120396 0.2794)
			(end -0.12065 0.2794)
			(stroke
				(width 0.1)
				(type default)
			)
			(layer "F.Fab")
		)
		(fp_line
			(start -0.12065 -0.2794)
			(end 0.12065 -0.2794)
			(stroke
				(width 0.1)
				(type default)
			)
			(layer "F.Fab")
		)
		(fp_line
			(start 0.12065 -0.2794)
			(end 0.12065 -0.3048)
			(stroke
				(width 0.1)
				(type default)
			)
			(layer "F.Fab")
		)
		(fp_line
			(start 0.12065 -0.3048)
			(end 0.67945 -0.3048)
			(stroke
				(width 0.1)
				(type default)
			)
			(layer "F.Fab")
		)
		(fp_line
			(start 0.67945 -0.3048)
			(end 0.67945 0.3048)
			(stroke
				(width 0.1)
				(type default)
			)
			(layer "F.Fab")
		)
		(fp_line
			(start -0.67945 -0.305054)
			(end -0.12065 -0.305054)
			(stroke
				(width 0.1)
				(type default)
			)
			(layer "F.Fab")
		)
		(fp_line
			(start -0.12065 -0.305054)
			(end -0.12065 -0.2794)
			(stroke
				(width 0.1)
				(type default)
			)
			(layer "F.Fab")
		)
		(pad "1" smd circle
			(at -0.40005 0 270)
			(size 0 0)
			(layers "F.Cu" "F.Mask" "F.Paste")
			(net "FM_THERMTRIP_DLY_LVC1_R_N")
		)
		(pad "2" smd circle
			(at 0.40005 0 270)
			(size 0 0)
			(layers "F.Cu" "F.Mask" "F.Paste")
			(net "FM_THERMTRIP_DLY_LVC1_N")
		)
	)
)
